# T6G (Grand Teton) — schematic netlist excerpt (pin names and nets, part order shuffled) for the footprints in the layout excerpt that follows; sources: Cadence DE-HDL packaged netlist, KiCad conversion of 04192023_DAF0TMB3IC0_F0TG_MB_C_brd_V02_OCP.brd

R1256  Q_RES  0 5% CHIP  pkg 0402LF  page 258 : A = PVDD18_S5_P1_ADC ; B = PVDD18_S5_P1_ADC_TIC
R5234  Q_RES  0 5% CHIP  pkg 0402LF  page 234 : A = USB2_HUB_BUF_SWB_R_DP ; B = USB2_HUB_BUF_SWB_DP

(kicad_pcb
	(version 20260206)
	(generator "pcbnew")
	(generator_version "10.0")
	(general
		(thickness 1.6)
		(legacy_teardrops no)
	)
	(paper "A4")
	(title_block
		(title "04192023_DAF0TMB3IC0_F0TG_MB_C_brd_V02_OCP.brd")
		(comment 1 "Grand Teton / footprints 7355-7356 of 8354")
	)
	(layers
		(0 "F.Cu" signal "TOP")
		(4 "In1.Cu" signal "GND")
		(6 "In2.Cu" signal "IN1")
		(8 "In3.Cu" signal "GND1")
		(10 "In4.Cu" signal "IN2")
		(12 "In5.Cu" signal "GND2")
		(14 "In6.Cu" signal "IN3")
		(16 "In7.Cu" signal "GND3")
		(18 "In8.Cu" signal "VCC")
		(20 "In9.Cu" signal "VCC1")
		(22 "In10.Cu" signal "GND4")
		(24 "In11.Cu" signal "IN4")
		(26 "In12.Cu" signal "GND5")
		(28 "In13.Cu" signal "IN5")
		(30 "In14.Cu" signal "GND6")
		(32 "In15.Cu" signal "IN6")
		(34 "In16.Cu" signal "GND7")
		(2 "B.Cu" signal "BOTTOM")
		(9 "F.Adhes" user "F.Adhesive")
		(11 "B.Adhes" user "B.Adhesive")
		(13 "F.Paste" user "Package Geometry/Pastemask Top")
		(15 "B.Paste" user "Package Geometry/Pastemask Bottom")
		(5 "F.SilkS" user "Ref Des/Silkscreen Top")
		(7 "B.SilkS" user "Ref Des/Silkscreen Bottom")
		(1 "F.Mask" user "Board Geometry/Soldermask Top")
		(3 "B.Mask" user "Board Geometry/Soldermask Bottom")
		(17 "Dwgs.User" user "User.Drawings")
		(19 "Cmts.User" user "User.Comments")
		(21 "Eco1.User" user "User.Eco1")
		(23 "Eco2.User" user "User.Eco2")
		(25 "Edge.Cuts" user "Board Geometry/Outline")
		(27 "Margin" user)
		(31 "F.CrtYd" user "Package Geometry/Place Bound Top")
		(29 "B.CrtYd" user "Package Geometry/Place Bound Bottom")
		(35 "F.Fab" user "Ref Des/Assembly Top")
		(33 "B.Fab" user "Ref Des/Assembly Bottom")
	)
	(footprint ""
		(layer "B.Cu")
		(at 231.029002 -329.365102)
		(property "Reference" "R1256"
			(at 0 0 0)
			(layer "B.SilkS")
			(hide yes)
			(effects
				(font
					(size 1.27 1.27)
				)
				(justify mirror)
			)
		)
		(property "Value" ""
			(at 0 0 0)
			(layer "B.Fab")
			(effects
				(font
					(size 1.27 1.27)
				)
				(justify mirror)
			)
		)
		(duplicate_pad_numbers_are_jumpers no)
		(fp_line
			(start -0.7874 -0.4064)
			(end -0.7874 0.4064)
			(stroke
				(width 0.1524)
				(type default)
			)
			(layer "B.SilkS")
		)
		(fp_line
			(start -0.7874 0.4064)
			(end 0.7874 0.4064)
			(stroke
				(width 0.1524)
				(type default)
			)
			(layer "B.SilkS")
		)
		(fp_line
			(start 0.7874 -0.4064)
			(end -0.7874 -0.4064)
			(stroke
				(width 0.1524)
				(type default)
			)
			(layer "B.SilkS")
		)
		(fp_line
			(start 0.7874 0.4064)
			(end 0.7874 -0.4064)
			(stroke
				(width 0.1524)
				(type default)
			)
			(layer "B.SilkS")
		)
		(fp_line
			(start -0.67945 -0.3048)
			(end -0.67945 0.3048)
			(stroke
				(width 0.1)
				(type default)
			)
			(layer "B.Fab")
		)
		(fp_line
			(start -0.67945 0.3048)
			(end -0.120396 0.3048)
			(stroke
				(width 0.1)
				(type default)
			)
			(layer "B.Fab")
		)
		(fp_line
			(start -0.12065 -0.3048)
			(end -0.67945 -0.3048)
			(stroke
				(width 0.1)
				(type default)
			)
			(layer "B.Fab")
		)
		(fp_line
			(start -0.12065 -0.2794)
			(end -0.12065 -0.3048)
			(stroke
				(width 0.1)
				(type default)
			)
			(layer "B.Fab")
		)
		(fp_line
			(start -0.120396 0.2794)
			(end 0.12065 0.2794)
			(stroke
				(width 0.1)
				(type default)
			)
			(layer "B.Fab")
		)
		(fp_line
			(start -0.120396 0.3048)
			(end -0.120396 0.2794)
			(stroke
				(width 0.1)
				(type default)
			)
			(layer "B.Fab")
		)
		(fp_line
			(start 0.12065 -0.305054)
			(end 0.12065 -0.2794)
			(stroke
				(width 0.1)
				(type default)
			)
			(layer "B.Fab")
		)
		(fp_line
			(start 0.12065 -0.2794)
			(end -0.12065 -0.2794)
			(stroke
				(width 0.1)
				(type default)
			)
			(layer "B.Fab")
		)
		(fp_line
			(start 0.12065 0.2794)
			(end 0.12065 0.3048)
			(stroke
				(width 0.1)
				(type default)
			)
			(layer "B.Fab")
		)
		(fp_line
			(start 0.12065 0.3048)
			(end 0.67945 0.3048)
			(stroke
				(width 0.1)
				(type default)
			)
			(layer "B.Fab")
		)
		(fp_line
			(start 0.67945 -0.305054)
			(end 0.12065 -0.305054)
			(stroke
				(width 0.1)
				(type default)
			)
			(layer "B.Fab")
		)
		(fp_line
			(start 0.67945 0.3048)
			(end 0.67945 -0.305054)
			(stroke
				(width 0.1)
				(type default)
			)
			(layer "B.Fab")
		)
		(pad "1" smd rect
			(at 0.40005 0)
			(size 0.4572 0.508)
			(layers "B.Cu" "B.Mask" "B.Paste")
			(net "PVDD18_S5_P1_ADC")
		)
		(pad "2" smd rect
			(at -0.40005 0)
			(size 0.4572 0.508)
			(layers "B.Cu" "B.Mask" "B.Paste")
			(net "PVDD18_S5_P1_ADC_TIC")
		)
	)
	(footprint ""
		(layer "B.Cu")
		(at 50.718974 -418.707316 180)
		(property "Reference" "R5234"
			(at 0 0 0)
			(layer "B.SilkS")
			(hide yes)
			(effects
				(font
					(size 1.27 1.27)
				)
				(justify mirror)
			)
		)
		(property "Value" ""
			(at 0 0 0)
			(layer "B.Fab")
			(effects
				(font
					(size 1.27 1.27)
				)
				(justify mirror)
			)
		)
		(duplicate_pad_numbers_are_jumpers no)
		(fp_line
			(start 0.7874 0.4064)
			(end 0.7874 -0.4064)
			(stroke
				(width 0.1524)
				(type default)
			)
			(layer "B.SilkS")
		)
		(fp_line
			(start 0.7874 -0.4064)
			(end -0.7874 -0.4064)
			(stroke
				(width 0.1524)
				(type default)
			)
			(layer "B.SilkS")
		)
		(fp_line
			(start -0.7874 0.4064)
			(end 0.7874 0.4064)
			(stroke
				(width 0.1524)
				(type default)
			)
			(layer "B.SilkS")
		)
		(fp_line
			(start -0.7874 -0.4064)
			(end -0.7874 0.4064)
			(stroke
				(width 0.1524)
				(type default)
			)
			(layer "B.SilkS")
		)
		(fp_line
			(start 0.67945 0.3048)
			(end 0.67945 -0.305054)
			(stroke
				(width 0.1)
				(type default)
			)
			(layer "B.Fab")
		)
		(fp_line
			(start 0.67945 -0.305054)
			(end 0.12065 -0.305054)
			(stroke
				(width 0.1)
				(type default)
			)
			(layer "B.Fab")
		)
		(fp_line
			(start 0.12065 0.3048)
			(end 0.67945 0.3048)
			(stroke
				(width 0.1)
				(type default)
			)
			(layer "B.Fab")
		)
		(fp_line
			(start 0.12065 0.2794)
			(end 0.12065 0.3048)
			(stroke
				(width 0.1)
				(type default)
			)
			(layer "B.Fab")
		)
		(fp_line
			(start 0.12065 -0.2794)
			(end -0.12065 -0.2794)
			(stroke
				(width 0.1)
				(type default)
			)
			(layer "B.Fab")
		)
		(fp_line
			(start 0.12065 -0.305054)
			(end 0.12065 -0.2794)
			(stroke
				(width 0.1)
				(type default)
			)
			(layer "B.Fab")
		)
		(fp_line
			(start -0.120396 0.3048)
			(end -0.120396 0.2794)
			(stroke
				(width 0.1)
				(type default)
			)
			(layer "B.Fab")
		)
		(fp_line
			(start -0.120396 0.2794)
			(end 0.12065 0.2794)
			(stroke
				(width 0.1)
				(type default)
			)
			(layer "B.Fab")
		)
		(fp_line
			(start -0.12065 -0.2794)
			(end -0.12065 -0.3048)
			(stroke
				(width 0.1)
				(type default)
			)
			(layer "B.Fab")
		)
		(fp_line
			(start -0.12065 -0.3048)
			(end -0.67945 -0.3048)
			(stroke
				(width 0.1)
				(type default)
			)
			(layer "B.Fab")
		)
		(fp_line
			(start -0.67945 0.3048)
			(end -0.120396 0.3048)
			(stroke
				(width 0.1)
				(type default)
			)
			(layer "B.Fab")
		)
		(fp_line
			(start -0.67945 -0.3048)
			(end -0.67945 0.3048)
			(stroke
				(width 0.1)
				(type default)
			)
			(layer "B.Fab")
		)
		(pad "1" smd circle
			(at 0.40005 0)
			(size 0 0)
			(layers "B.Cu" "B.Mask" "B.Paste")
			(net "USB2_HUB_BUF_SWB_R_DP")
		)
		(pad "2" smd circle
			(at -0.40005 0)
			(size 0 0)
			(layers "B.Cu" "B.Mask" "B.Paste")
			(net "USB2_HUB_BUF_SWB_DP")
		)
	)
)
